FILE_TYPE = MACRO_DRAWING;
SET COLOR_WIRE YELLOW;
SET COLOR_PROP MONO;
SET COLOR_DOT WHITE;
SET COLOR_ARC YELLOW;
SET COLOR_BODY GREEN;
SET COLOR_NOTE MONO;
SET PROP_DISPLAY VALUE;
SET PAGE_NUMBER P246;
FORCEADD OFFPAGE..1
(-7125 2500);
FORCEPROP 2 LAST $XR1 146 
J 0
(-7497 2500);
DISPLAY 0.638298 (-7497 2500);
PAINT MONO (-7497 2500);
FORCEPROP 2 LAST $XR0 137 
J 0
(-7377 2500);
DISPLAY 0.638298 (-7377 2500);
PAINT MONO (-7377 2500);
FORCEPROP 2 LAST CDS_LIB mstr_standard
J 0
(-7125 2500);
DISPLAY 1.531915 (-7125 2500);
PAINT ORANGE (-7125 2500);
DISPLAY INVISIBLE (-7125 2500);
FORCEPROP 2 LAST PATH I1
J 0
(-7375 2550);
DISPLAY 1.021277 (-7375 2550);
PAINT ORANGE (-7375 2550);
DISPLAY INVISIBLE (-7375 2550);
FORCEPROP 1 LAST OFFPAGE TRUE
J 0
(-6800 2375);
PAINT GREEN (-6800 2375);
DISPLAY INVISIBLE (-6800 2375);
FORCEPROP 1 LAST COMMENT_BODY TRUE
J 0
(-7000 2400);
DISPLAY 0.978723 (-7000 2400);
PAINT PEACH (-7000 2400);
DISPLAY INVISIBLE (-7000 2400);
FORCEADD RES..2
R 2
(-5775 3200);
FORCEPROP 1 LAST PART_NUMBER G21796-072
J 2
(-5815 3075);
DISPLAY 0.617021 (-5815 3075);
PAINT BLUE (-5815 3075);
FORCEPROP 1 LAST WATTAGE 1/16W
J 2
(-5815 3125);
DISPLAY 0.617021 (-5815 3125);
PAINT SKYBLUE (-5815 3125);
FORCEPROP 1 LAST PACK_TYPE 0402
J 2
(-5815 3025);
DISPLAY 0.617021 (-5815 3025);
PAINT SKYBLUE (-5815 3025);
FORCEPROP 1 LAST TOLERANCE 1%
J 2
(-5820 3175);
DISPLAY 0.617021 (-5820 3175);
PAINT SKYBLUE (-5820 3175);
FORCEPROP 1 LAST VALUE 4.75K
J 2
(-5820 3275);
DISPLAY 0.617021 (-5820 3275);
PAINT SKYBLUE (-5820 3275);
FORCEPROP 1 LASTPIN (-5775 3100) $PN 2
J 2
(-5780 3110);
DISPLAY 0.617021 (-5780 3110);
PAINT ORANGE (-5780 3110);
FORCEPROP 1 LAST LOCATION RN8F3
J 2
(-5820 3325);
DISPLAY 0.617021 (-5820 3325);
PAINT AQUA (-5820 3325);
FORCEPROP 1 LASTPIN (-5775 3300) $PN 1
J 2
(-5780 3262);
DISPLAY 0.617021 (-5780 3262);
PAINT ORANGE (-5780 3262);
FORCEPROP 1 LAST MATERIAL CHIP
J 2
(-5815 3225);
DISPLAY 0.617021 (-5815 3225);
PAINT SKYBLUE (-5815 3225);
FORCEPROP 0 LAST CDS_LOCATION RN8F3
J 0
(-5800 3375);
PAINT MONO (-5800 3375);
DISPLAY INVISIBLE (-5800 3375);
FORCEPROP 0 LAST CDS_SEC 1
J 0
(-5800 3375);
PAINT MONO (-5800 3375);
DISPLAY INVISIBLE (-5800 3375);
FORCEPROP 2 LAST CDS_LIB mstr_discrete
J 0
(-5775 3200);
PAINT ORANGE (-5775 3200);
DISPLAY INVISIBLE (-5775 3200);
FORCEPROP 2 LAST BOM_COST SM_MEM
J 0
(-5800 3425);
DISPLAY 1.021277 (-5800 3425);
PAINT ORANGE (-5800 3425);
DISPLAY INVISIBLE (-5800 3425);
FORCEPROP 2 LAST SEC_TYPE 0402
J 0
(-5825 3425);
DISPLAY 1.021277 (-5825 3425);
PAINT ORANGE (-5825 3425);
DISPLAY INVISIBLE (-5825 3425);
FORCEPROP 2 LAST ROOM BMC_BOOT_SPI
J 0
(-5800 3375);
DISPLAY 1.021277 (-5800 3375);
PAINT ORANGE (-5800 3375);
DISPLAY INVISIBLE (-5800 3375);
FORCEPROP 2 LAST SEC 1
J 0
(-5825 3425);
DISPLAY 0.680851 (-5825 3425);
PAINT MONO (-5825 3425);
DISPLAY INVISIBLE (-5825 3425);
FORCEPROP 1 LAST PATH I11
J 2
(-5825 3375);
DISPLAY 0.978723 (-5825 3375);
PAINT WHITE (-5825 3375);
DISPLAY INVISIBLE (-5825 3375);
FORCEADD RES..2
R 2
(-5225 3225);
FORCEPROP 1 LAST PACK_TYPE 0402
J 2
(-5265 3050);
DISPLAY 0.617021 (-5265 3050);
PAINT SKYBLUE (-5265 3050);
FORCEPROP 1 LAST WATTAGE 1/16W
J 2
(-5265 3150);
DISPLAY 0.617021 (-5265 3150);
PAINT SKYBLUE (-5265 3150);
FORCEPROP 1 LAST VALUE 4.75K
J 2
(-5270 3300);
DISPLAY 0.617021 (-5270 3300);
PAINT SKYBLUE (-5270 3300);
FORCEPROP 1 LAST MATERIAL EMPTY
J 2
(-5265 3250);
DISPLAY 0.617021 (-5265 3250);
PAINT RED (-5265 3250);
FORCEPROP 1 LAST TOLERANCE 1%
J 2
(-5270 3200);
DISPLAY 0.617021 (-5270 3200);
PAINT SKYBLUE (-5270 3200);
FORCEPROP 1 LAST LOCATION RN8F4
J 2
(-5270 3350);
DISPLAY 0.617021 (-5270 3350);
PAINT AQUA (-5270 3350);
FORCEPROP 1 LASTPIN (-5225 3325) $PN 1
J 2
(-5230 3287);
DISPLAY 0.617021 (-5230 3287);
PAINT ORANGE (-5230 3287);
FORCEPROP 1 LASTPIN (-5225 3125) $PN 2
J 2
(-5230 3135);
DISPLAY 0.617021 (-5230 3135);
PAINT ORANGE (-5230 3135);
FORCEPROP 1 LAST PART_NUMBER G21796-072
J 2
(-5265 3100);
DISPLAY 0.617021 (-5265 3100);
PAINT BLUE (-5265 3100);
FORCEPROP 0 LAST CDS_SEC 1
J 0
(-5250 3400);
PAINT MONO (-5250 3400);
DISPLAY INVISIBLE (-5250 3400);
FORCEPROP 2 LAST CDS_LIB mstr_discrete
J 0
(-5225 3225);
PAINT ORANGE (-5225 3225);
DISPLAY INVISIBLE (-5225 3225);
FORCEPROP 0 LAST CDS_LOCATION RN8F4
J 0
(-5250 3400);
PAINT MONO (-5250 3400);
DISPLAY INVISIBLE (-5250 3400);
FORCEPROP 2 LAST SEC_TYPE 0402
J 0
(-5275 3450);
DISPLAY 1.021277 (-5275 3450);
PAINT ORANGE (-5275 3450);
DISPLAY INVISIBLE (-5275 3450);
FORCEPROP 2 LAST SEC 1
J 0
(-5275 3450);
DISPLAY 0.680851 (-5275 3450);
PAINT MONO (-5275 3450);
DISPLAY INVISIBLE (-5275 3450);
FORCEPROP 1 LAST PATH I12
J 2
(-5275 3400);
DISPLAY 0.978723 (-5275 3400);
PAINT WHITE (-5275 3400);
DISPLAY INVISIBLE (-5275 3400);
FORCEPROP 2 LAST BOM_COST SM_MEM
J 0
(-5250 3450);
DISPLAY 1.021277 (-5250 3450);
PAINT ORANGE (-5250 3450);
DISPLAY INVISIBLE (-5250 3450);
FORCEPROP 2 LAST ROOM BMC_BOOT_SPI
J 0
(-5250 3400);
DISPLAY 1.021277 (-5250 3400);
PAINT ORANGE (-5250 3400);
DISPLAY INVISIBLE (-5250 3400);
FORCEADD GND..1
(-3025 2300);
FORCEPROP 3 LASTPIN (-3025 2350) SIG_NAME GND\g
J 0
(-3015 2360);
DISPLAY 0.659574 (-3015 2360);
PAINT MONO (-3015 2360);
DISPLAY INVISIBLE (-3015 2360);
FORCEPROP 1 LAST PATH I13
J 0
(-2950 2300);
DISPLAY 0.872340 (-2950 2300);
PAINT AQUA (-2950 2300);
DISPLAY INVISIBLE (-2950 2300);
FORCEPROP 2 LAST CDS_LIB mstr_symbols
J 0
(-3025 2300);
PAINT ORANGE (-3025 2300);
DISPLAY INVISIBLE (-3025 2300);
FORCEPROP 1 LAST SIZE 1B
J 0
(-2950 2250);
DISPLAY 1.170213 (-2950 2250);
PAINT GREEN (-2950 2250);
DISPLAY INVISIBLE (-2950 2250);
FORCEPROP 1 LAST VOLTAGE 0
J 0
(-3025 2300);
PAINT SKYBLUE (-3025 2300);
DISPLAY INVISIBLE (-3025 2300);
FORCEPROP 1 LAST BODY_TYPE PLUMBING
J 0
(-3070 2257);
DISPLAY 0.340426 (-3070 2257);
PAINT GREEN (-3070 2257);
DISPLAY INVISIBLE (-3070 2257);
FORCEPROP 1 LAST HDL_POWER GND
J 0
(-3025 2450);
DISPLAY 1.170213 (-3025 2450);
PAINT GREEN (-3025 2450);
DISPLAY INVISIBLE (-3025 2450);
FORCEADD GND..1
(-2700 2950);
FORCEPROP 3 LASTPIN (-2700 3000) SIG_NAME GND\g
J 0
(-2690 3010);
DISPLAY 0.659574 (-2690 3010);
PAINT MONO (-2690 3010);
DISPLAY INVISIBLE (-2690 3010);
FORCEPROP 1 LAST SIZE 1B
J 0
(-2625 2900);
DISPLAY 0.872340 (-2625 2900);
PAINT AQUA (-2625 2900);
DISPLAY INVISIBLE (-2625 2900);
FORCEPROP 2 LAST CDS_LIB mstr_symbols
J 0
(-2700 2950);
PAINT ORANGE (-2700 2950);
DISPLAY INVISIBLE (-2700 2950);
FORCEPROP 1 LAST VOLTAGE 0.0V
J 0
(-2745 2907);
DISPLAY 0.340426 (-2745 2907);
PAINT GREEN (-2745 2907);
DISPLAY INVISIBLE (-2745 2907);
FORCEPROP 1 LAST PATH I14
J 0
(-2625 2950);
DISPLAY 0.872340 (-2625 2950);
PAINT AQUA (-2625 2950);
DISPLAY INVISIBLE (-2625 2950);
FORCEPROP 1 LAST BODY_TYPE PLUMBING
J 0
(-2745 2907);
DISPLAY 0.340426 (-2745 2907);
PAINT GREEN (-2745 2907);
DISPLAY INVISIBLE (-2745 2907);
FORCEPROP 1 LAST HDL_POWER GND
J 0
(-2700 3100);
DISPLAY 0.872340 (-2700 3100);
PAINT GREEN (-2700 3100);
DISPLAY INVISIBLE (-2700 3100);
FORCEADD W25Q256..1
(-3675 2750);
FORCEPROP 2 LASTPIN (-4225 2700) $PN 15
J 2
(-4235 2710);
DISPLAY 0.617021 (-4235 2710);
PAINT ORANGE (-4235 2710);
FORCEPROP 2 LASTPIN (-4225 2850) $PN 1
J 2
(-4235 2860);
DISPLAY 0.617021 (-4235 2860);
PAINT ORANGE (-4235 2860);
FORCEPROP 2 LASTPIN (-3125 2750) $PN 12
J 0
(-3115 2760);
DISPLAY 0.617021 (-3115 2760);
PAINT ORANGE (-3115 2760);
FORCEPROP 1 LAST MATERIAL IC
J 0
(-4175 3150);
DISPLAY 0.617021 (-4175 3150);
PAINT SKYBLUE (-4175 3150);
FORCEPROP 2 LASTPIN (-3125 2700) $PN 13
J 0
(-3115 2710);
DISPLAY 0.617021 (-3115 2710);
PAINT ORANGE (-3115 2710);
FORCEPROP 2 LASTPIN (-3125 2850) $PN 6
J 0
(-3115 2860);
DISPLAY 0.617021 (-3115 2860);
PAINT ORANGE (-3115 2860);
FORCEPROP 2 LASTPIN (-4225 2950) $PN 2
J 2
(-4235 2960);
DISPLAY 0.617021 (-4235 2960);
PAINT ORANGE (-4235 2960);
FORCEPROP 2 LASTPIN (-4225 2750) $PN 8
J 2
(-4235 2760);
DISPLAY 0.617021 (-4235 2760);
PAINT ORANGE (-4235 2760);
FORCEPROP 2 LASTPIN (-3125 2900) $PN 5
J 0
(-3115 2910);
DISPLAY 0.617021 (-3115 2910);
PAINT ORANGE (-3115 2910);
FORCEPROP 2 LASTPIN (-3125 2650) $PN 14
J 0
(-3115 2660);
DISPLAY 0.617021 (-3115 2660);
PAINT ORANGE (-3115 2660);
FORCEPROP 2 LASTPIN (-3125 2950) $PN 4
J 0
(-3115 2960);
DISPLAY 0.617021 (-3115 2960);
PAINT ORANGE (-3115 2960);
FORCEPROP 2 LASTPIN (-4225 2500) $PN 7
J 2
(-4235 2510);
DISPLAY 0.617021 (-4235 2510);
PAINT ORANGE (-4235 2510);
FORCEPROP 2 LASTPIN (-4225 2600) $PN 16
J 2
(-4235 2610);
DISPLAY 0.617021 (-4235 2610);
PAINT ORANGE (-4235 2610);
FORCEPROP 2 LASTPIN (-4225 2800) $PN 9
J 2
(-4235 2810);
DISPLAY 0.617021 (-4235 2810);
PAINT ORANGE (-4235 2810);
FORCEPROP 2 LASTPIN (-4225 2450) $PN 3
J 2
(-4235 2460);
DISPLAY 0.617021 (-4235 2460);
PAINT ORANGE (-4235 2460);
FORCEPROP 1 LAST PART_NUMBER H25002-001
J 0
(-4175 2250);
DISPLAY 0.617021 (-4175 2250);
PAINT BLUE (-4175 2250);
FORCEPROP 2 LASTPIN (-3125 2800) $PN 11
J 0
(-3115 2810);
DISPLAY 0.617021 (-3115 2810);
PAINT ORANGE (-3115 2810);
FORCEPROP 2 LASTPIN (-3125 2500) $PN 10
J 0
(-3115 2510);
DISPLAY 0.617021 (-3115 2510);
PAINT ORANGE (-3115 2510);
FORCEPROP 1 LAST LOCATION UN8F2
J 0
(-4025 3175);
DISPLAY 0.617021 (-4025 3175);
PAINT AQUA (-4025 3175);
FORCEPROP 2 LAST SEC 1
J 0
(-4025 3225);
DISPLAY 0.680851 (-4025 3225);
PAINT MONO (-4025 3225);
DISPLAY INVISIBLE (-4025 3225);
FORCEPROP 2 LAST BOM_COST SM_MEM
J 0
(-4175 3250);
DISPLAY 1.021277 (-4175 3250);
PAINT ORANGE (-4175 3250);
DISPLAY INVISIBLE (-4175 3250);
FORCEPROP 2 LAST SEC_TYPE XSOI
J 0
(-4025 3225);
DISPLAY 1.021277 (-4025 3225);
PAINT ORANGE (-4025 3225);
DISPLAY INVISIBLE (-4025 3225);
FORCEPROP 2 LAST ROOM BMC_BOOT_SPI
J 0
(-4175 3200);
DISPLAY 1.021277 (-4175 3200);
PAINT ORANGE (-4175 3200);
DISPLAY INVISIBLE (-4175 3200);
FORCEPROP 1 LAST PACK_TYPE XSOI
J 0
(-4175 3250);
PAINT SKYBLUE (-4175 3250);
DISPLAY INVISIBLE (-4175 3250);
FORCEPROP 2 LAST CDS_LIB mstr_memory
J 0
(-3675 2750);
PAINT MONO (-3675 2750);
DISPLAY INVISIBLE (-3675 2750);
FORCEPROP 0 LAST CDS_LOCATION UN8F2
J 0
(-4025 3225);
PAINT MONO (-4025 3225);
DISPLAY INVISIBLE (-4025 3225);
FORCEPROP 0 LAST CDS_SEC 1
J 0
(-4025 3225);
PAINT MONO (-4025 3225);
DISPLAY INVISIBLE (-4025 3225);
FORCEPROP 1 LAST PATH I17
J 0
(-3675 3150);
PAINT GREEN (-3675 3150);
DISPLAY INVISIBLE (-3675 3150);
FORCEADD OFFPAGE..1
(-7125 2800);
FORCEPROP 2 LAST $XR0 137 
J 0
(-7377 2800);
DISPLAY 0.638298 (-7377 2800);
PAINT MONO (-7377 2800);
FORCEPROP 2 LAST PATH I18
J 0
(-7075 2875);
DISPLAY 1.021277 (-7075 2875);
PAINT ORANGE (-7075 2875);
DISPLAY INVISIBLE (-7075 2875);
FORCEPROP 2 LAST CDS_LIB mstr_standard
J 0
(-7125 2800);
PAINT MONO (-7125 2800);
DISPLAY INVISIBLE (-7125 2800);
FORCEPROP 1 LAST OFFPAGE TRUE
J 0
(-6800 2675);
PAINT GREEN (-6800 2675);
DISPLAY INVISIBLE (-6800 2675);
FORCEPROP 1 LAST COMMENT_BODY TRUE
J 0
(-7000 2700);
DISPLAY 0.978723 (-7000 2700);
PAINT PEACH (-7000 2700);
DISPLAY INVISIBLE (-7000 2700);
FORCEADD 82KR2F-1-GP..1
(-6225 2300);
FORCEPROP 2 LAST ATTRIBUTE 82KOHM
J 0
(-6200 2275);
DISPLAY 0.638298 (-6200 2275);
PAINT GREEN (-6200 2275);
FORCEPROP 2 LAST TOLERANCE 1%
J 0
(-6200 2225);
DISPLAY 0.638298 (-6200 2225);
PAINT GREEN (-6200 2225);
FORCEPROP 1 LAST VALUE 82KR2F-1-GP
J 0
(-6200 2325);
DISPLAY 0.617021 (-6200 2325);
PAINT GREEN (-6200 2325);
FORCEPROP 1 LAST LOCATION RN8F6
J 0
(-6200 2380);
DISPLAY 0.617021 (-6200 2380);
PAINT GREEN (-6200 2380);
FORCEPROP 2 LAST PACK_SIZE 0402
J 0
(-6200 2125);
DISPLAY 0.638298 (-6200 2125);
PAINT GREEN (-6200 2125);
FORCEPROP 2 LAST RATED 1/16W
J 0
(-6200 2175);
DISPLAY 0.638298 (-6200 2175);
PAINT GREEN (-6200 2175);
FORCEPROP 1 LAST CDS_LMAN_SYM_OUTLINE -50,75,50,-75
J 0
(-6225 2300);
DISPLAY 0.468085 (-6225 2300);
PAINT GREEN (-6225 2300);
DISPLAY INVISIBLE (-6225 2300);
FORCEPROP 1 LAST PATH I19
J 0
(-6225 2300);
DISPLAY 0.617021 (-6225 2300);
PAINT GREEN (-6225 2300);
DISPLAY INVISIBLE (-6225 2300);
FORCEPROP 2 LAST CDS_LIB w_hdl
J 0
(-6225 2300);
PAINT MONO (-6225 2300);
DISPLAY INVISIBLE (-6225 2300);
FORCEPROP 1 LAST PART_NUMBER 64.82025.6DL
J 0
(-6225 2300);
DISPLAY 0.617021 (-6225 2300);
PAINT GREEN (-6225 2300);
DISPLAY INVISIBLE (-6225 2300);
FORCEPROP 1 LAST PACK_TYPE SMD-RG
J 0
(-6225 2300);
DISPLAY 0.617021 (-6225 2300);
PAINT GREEN (-6225 2300);
DISPLAY INVISIBLE (-6225 2300);
FORCEADD OFFPAGE..1
(-7125 2600);
FORCEPROP 2 LAST $XR2 162 
J 0
(-7617 2600);
DISPLAY 0.638298 (-7617 2600);
PAINT MONO (-7617 2600);
FORCEPROP 2 LAST $XR1 150 
J 0
(-7497 2600);
DISPLAY 0.638298 (-7497 2600);
PAINT MONO (-7497 2600);
FORCEPROP 2 LAST $XR0 146 
J 0
(-7377 2600);
DISPLAY 0.638298 (-7377 2600);
PAINT MONO (-7377 2600);
FORCEPROP 2 LAST CDS_LIB mstr_standard
J 0
(-7125 2600);
DISPLAY 1.531915 (-7125 2600);
PAINT ORANGE (-7125 2600);
DISPLAY INVISIBLE (-7125 2600);
FORCEPROP 2 LAST PATH I2
J 0
(-7375 2650);
DISPLAY 1.021277 (-7375 2650);
PAINT ORANGE (-7375 2650);
DISPLAY INVISIBLE (-7375 2650);
FORCEPROP 1 LAST OFFPAGE TRUE
J 0
(-6800 2475);
PAINT GREEN (-6800 2475);
DISPLAY INVISIBLE (-6800 2475);
FORCEPROP 1 LAST COMMENT_BODY TRUE
J 0
(-7000 2500);
DISPLAY 0.978723 (-7000 2500);
PAINT PEACH (-7000 2500);
DISPLAY INVISIBLE (-7000 2500);
FORCEADD RES..2
R 2
(-6225 3225);
FORCEPROP 1 LAST PART_NUMBER G21796-072
J 2
(-6265 3100);
DISPLAY 0.617021 (-6265 3100);
PAINT BLUE (-6265 3100);
FORCEPROP 1 LAST WATTAGE 1/16W
J 2
(-6265 3150);
DISPLAY 0.617021 (-6265 3150);
PAINT SKYBLUE (-6265 3150);
FORCEPROP 1 LAST PACK_TYPE 0402
J 2
(-6265 3050);
DISPLAY 0.617021 (-6265 3050);
PAINT SKYBLUE (-6265 3050);
FORCEPROP 1 LAST LOCATION RN8F2
J 2
(-6270 3350);
DISPLAY 0.617021 (-6270 3350);
PAINT AQUA (-6270 3350);
FORCEPROP 1 LAST VALUE 4.75K
J 2
(-6270 3300);
DISPLAY 0.617021 (-6270 3300);
PAINT SKYBLUE (-6270 3300);
FORCEPROP 1 LAST MATERIAL EMPTY
J 2
(-6265 3250);
DISPLAY 0.617021 (-6265 3250);
PAINT RED (-6265 3250);
FORCEPROP 1 LAST TOLERANCE 1%
J 2
(-6270 3200);
DISPLAY 0.617021 (-6270 3200);
PAINT SKYBLUE (-6270 3200);
FORCEPROP 1 LASTPIN (-6225 3325) $PN 1
J 2
(-6230 3287);
DISPLAY 0.787234 (-6230 3287);
PAINT ORANGE (-6230 3287);
FORCEPROP 1 LASTPIN (-6225 3125) $PN 2
J 2
(-6230 3135);
DISPLAY 0.787234 (-6230 3135);
PAINT ORANGE (-6230 3135);
FORCEPROP 2 LAST SEC_TYPE 0402
J 0
(-6275 3450);
DISPLAY 1.021277 (-6275 3450);
PAINT ORANGE (-6275 3450);
DISPLAY INVISIBLE (-6275 3450);
FORCEPROP 2 LAST SEC 1
J 0
(-6275 3450);
DISPLAY 0.680851 (-6275 3450);
PAINT MONO (-6275 3450);
DISPLAY INVISIBLE (-6275 3450);
FORCEPROP 2 LAST CDS_LIB mstr_discrete
J 0
(-6225 3225);
PAINT MONO (-6225 3225);
DISPLAY INVISIBLE (-6225 3225);
FORCEPROP 2 LAST ROOM BMC_BOOT_SPI
J 0
(-6250 3400);
DISPLAY 1.021277 (-6250 3400);
PAINT ORANGE (-6250 3400);
DISPLAY INVISIBLE (-6250 3400);
FORCEPROP 2 LAST BOM_COST SM_MEM
J 0
(-6250 3450);
DISPLAY 1.021277 (-6250 3450);
PAINT ORANGE (-6250 3450);
DISPLAY INVISIBLE (-6250 3450);
FORCEPROP 1 LAST PATH I20
J 2
(-6275 3400);
DISPLAY 0.978723 (-6275 3400);
PAINT WHITE (-6275 3400);
DISPLAY INVISIBLE (-6275 3400);
FORCEADD CAP_A..1
(-3000 3275);
FORCEPROP 1 LASTPIN (-3000 3175) $PN 2
J 0
(-2990 3155);
DISPLAY 0.617021 (-2990 3155);
PAINT ORANGE (-2990 3155);
FORCEPROP 1 LASTPIN (-3000 3375) $PN 1
J 0
(-2990 3355);
DISPLAY 0.617021 (-2990 3355);
PAINT ORANGE (-2990 3355);
FORCEPROP 1 LAST LOCATION CN8F1
J 0
(-2950 3375);
DISPLAY 0.617021 (-2950 3375);
PAINT AQUA (-2950 3375);
FORCEPROP 1 LAST VALUE 1.0UF
J 0
(-2950 3325);
DISPLAY 0.617021 (-2950 3325);
PAINT SKYBLUE (-2950 3325);
FORCEPROP 1 LAST VOLTAGE 6.3V
J 0
(-2950 3275);
DISPLAY 0.617021 (-2950 3275);
PAINT SKYBLUE (-2950 3275);
FORCEPROP 1 LAST MATERIAL X6S
J 0
(-2950 3175);
DISPLAY 0.617021 (-2950 3175);
PAINT SKYBLUE (-2950 3175);
FORCEPROP 1 LAST PACK_TYPE 0402V
J 0
(-2950 3075);
DISPLAY 0.617021 (-2950 3075);
PAINT SKYBLUE (-2950 3075);
FORCEPROP 1 LAST PART_NUMBER D97712-004
J 0
(-2950 3125);
DISPLAY 0.617021 (-2950 3125);
PAINT BLUE (-2950 3125);
FORCEPROP 1 LAST TOLERANCE 10%
J 0
(-2950 3225);
DISPLAY 0.617021 (-2950 3225);
PAINT SKYBLUE (-2950 3225);
FORCEPROP 1 LAST PATH I21
J 0
(-2950 3425);
DISPLAY 0.978723 (-2950 3425);
PAINT WHITE (-2950 3425);
DISPLAY INVISIBLE (-2950 3425);
FORCEPROP 2 LAST CDS_LIB dev_discrete
J 0
(-3000 3275);
PAINT ORANGE (-3000 3275);
DISPLAY INVISIBLE (-3000 3275);
FORCEPROP 2 LAST CDS_SEC 1
J 0
(-2950 3425);
PAINT ORANGE (-2950 3425);
DISPLAY INVISIBLE (-2950 3425);
FORCEPROP 2 LAST SEC_TYPE 0402V
J 0
(-2950 3475);
DISPLAY 1.021277 (-2950 3475);
PAINT ORANGE (-2950 3475);
DISPLAY INVISIBLE (-2950 3475);
FORCEPROP 2 LAST SEC 1
J 0
(-2950 3475);
DISPLAY 0.680851 (-2950 3475);
PAINT MONO (-2950 3475);
DISPLAY INVISIBLE (-2950 3475);
FORCEPROP 2 LAST ROOM VDDQ_KLM_PWR_VR
J 0
(-2950 3425);
DISPLAY 1.361702 (-2950 3425);
PAINT ORANGE (-2950 3425);
DISPLAY INVISIBLE (-2950 3425);
FORCEPROP 2 LAST CDS_LOCATION CN8F1
J 0
(-2950 3375);
DISPLAY 0.617021 (-2950 3375);
PAINT AQUA (-2950 3375);
DISPLAY INVISIBLE (-2950 3375);
FORCEADD CAP_A..1
R 2
(-2700 3275);
FORCEPROP 1 LAST LOCATION CN8F2
J 0
(-2650 3375);
DISPLAY 0.617021 (-2650 3375);
PAINT AQUA (-2650 3375);
FORCEPROP 1 LAST VALUE 0.01UF
J 0
(-2650 3325);
DISPLAY 0.617021 (-2650 3325);
PAINT SKYBLUE (-2650 3325);
FORCEPROP 1 LAST VOLTAGE 25V
J 0
(-2650 3275);
DISPLAY 0.617021 (-2650 3275);
PAINT SKYBLUE (-2650 3275);
FORCEPROP 1 LAST TOLERANCE 10%
J 0
(-2650 3225);
DISPLAY 0.617021 (-2650 3225);
PAINT SKYBLUE (-2650 3225);
FORCEPROP 1 LAST MATERIAL X7R
J 0
(-2650 3175);
DISPLAY 0.617021 (-2650 3175);
PAINT SKYBLUE (-2650 3175);
FORCEPROP 1 LASTPIN (-2700 3175) $PN 2
J 2
(-2710 3155);
DISPLAY 0.617021 (-2710 3155);
PAINT ORANGE (-2710 3155);
FORCEPROP 1 LASTPIN (-2700 3375) $PN 1
J 2
(-2710 3355);
DISPLAY 0.617021 (-2710 3355);
PAINT ORANGE (-2710 3355);
FORCEPROP 1 LAST PACK_TYPE 0402V
J 0
(-2650 3075);
DISPLAY 0.617021 (-2650 3075);
PAINT SKYBLUE (-2650 3075);
FORCEPROP 1 LAST PART_NUMBER A36096-045
J 0
(-2650 3125);
DISPLAY 0.617021 (-2650 3125);
PAINT BLUE (-2650 3125);
FORCEPROP 1 LAST PATH I22
J 2
(-2750 3425);
DISPLAY 0.978723 (-2750 3425);
PAINT WHITE (-2750 3425);
DISPLAY INVISIBLE (-2750 3425);
FORCEPROP 2 LAST ROOM DDR4_CH_M
J 0
(-2700 3275);
PAINT ORANGE (-2700 3275);
DISPLAY INVISIBLE (-2700 3275);
FORCEPROP 2 LAST SEC 1
J 0
(-2750 3475);
PAINT MONO (-2750 3475);
DISPLAY INVISIBLE (-2750 3475);
FORCEPROP 2 LAST SEC_TYPE 0402V
J 0
(-2750 3475);
DISPLAY 1.021277 (-2750 3475);
PAINT ORANGE (-2750 3475);
DISPLAY INVISIBLE (-2750 3475);
FORCEPROP 2 LAST CDS_SEC 1
J 0
(-2750 3425);
PAINT ORANGE (-2750 3425);
DISPLAY INVISIBLE (-2750 3425);
FORCEPROP 2 LAST CDS_LIB dev_discrete
J 0
(-2700 3275);
PAINT ORANGE (-2700 3275);
DISPLAY INVISIBLE (-2700 3275);
FORCEPROP 2 LAST BOM_COST MEM
J 0
(-2700 3275);
PAINT ORANGE (-2700 3275);
DISPLAY INVISIBLE (-2700 3275);
FORCEPROP 2 LAST CDS_LOCATION CN8F2
J 2
(-2750 3375);
DISPLAY 0.617021 (-2750 3375);
PAINT AQUA (-2750 3375);
DISPLAY INVISIBLE (-2750 3375);
FORCEADD OFFPAGE..1
(-7125 2700);
FORCEPROP 2 LAST $XR2 162 
J 0
(-7617 2700);
DISPLAY 0.638298 (-7617 2700);
PAINT MONO (-7617 2700);
FORCEPROP 2 LAST $XR1 150 
J 0
(-7497 2700);
DISPLAY 0.638298 (-7497 2700);
PAINT MONO (-7497 2700);
FORCEPROP 2 LAST $XR0 146 
J 0
(-7377 2700);
DISPLAY 0.638298 (-7377 2700);
PAINT MONO (-7377 2700);
FORCEPROP 2 LAST CDS_LIB mstr_standard
J 0
(-7125 2700);
DISPLAY 1.531915 (-7125 2700);
PAINT ORANGE (-7125 2700);
DISPLAY INVISIBLE (-7125 2700);
FORCEPROP 2 LAST PATH I3
J 0
(-7375 2750);
DISPLAY 1.021277 (-7375 2750);
PAINT ORANGE (-7375 2750);
DISPLAY INVISIBLE (-7375 2750);
FORCEPROP 1 LAST OFFPAGE TRUE
J 0
(-6800 2575);
PAINT GREEN (-6800 2575);
DISPLAY INVISIBLE (-6800 2575);
FORCEPROP 1 LAST COMMENT_BODY TRUE
J 0
(-7000 2600);
DISPLAY 0.978723 (-7000 2600);
PAINT PEACH (-7000 2600);
DISPLAY INVISIBLE (-7000 2600);
FORCEADD OFFPAGE..5
(-7125 2750);
FORCEPROP 2 LAST $XR2 150 
J 0
(-7620 2750);
DISPLAY 0.638298 (-7620 2750);
PAINT MONO (-7620 2750);
FORCEPROP 2 LAST $XR1 146 
J 0
(-7500 2750);
DISPLAY 0.638298 (-7500 2750);
PAINT MONO (-7500 2750);
FORCEPROP 2 LAST $XR0 162 
J 0
(-7380 2750);
DISPLAY 0.638298 (-7380 2750);
PAINT MONO (-7380 2750);
FORCEPROP 2 LAST PATH I4
J 0
(-7375 2800);
DISPLAY 1.021277 (-7375 2800);
PAINT ORANGE (-7375 2800);
DISPLAY INVISIBLE (-7375 2800);
FORCEPROP 2 LAST CDS_LIB mstr_standard
J 1
(-7125 2750);
PAINT ORANGE (-7125 2750);
DISPLAY INVISIBLE (-7125 2750);
FORCEPROP 1 LAST OFFPAGE TRUE
J 0
(-6800 2625);
PAINT GREEN (-6800 2625);
DISPLAY INVISIBLE (-6800 2625);
FORCEPROP 1 LAST COMMENT_BODY TRUE
J 0
(-7025 2675);
DISPLAY 1.170213 (-7025 2675);
PAINT GREEN (-7025 2675);
DISPLAY INVISIBLE (-7025 2675);
FORCEADD P3V3_STBY..1
(-5775 3600);
FORCEPROP 3 LASTPIN (-5775 3550) SIG_NAME P3V3_STBY\g
J 0
(-5765 3560);
DISPLAY 0.659574 (-5765 3560);
PAINT MONO (-5765 3560);
DISPLAY INVISIBLE (-5765 3560);
FORCEPROP 1 LAST SIZE 1B
J 0
(-5730 3622);
DISPLAY 0.340426 (-5730 3622);
PAINT GREEN (-5730 3622);
DISPLAY INVISIBLE (-5730 3622);
FORCEPROP 1 LAST VOLTAGE 3.3V
J 0
(-5820 3557);
DISPLAY 0.340426 (-5820 3557);
PAINT GREEN (-5820 3557);
DISPLAY INVISIBLE (-5820 3557);
FORCEPROP 1 LAST PATH I6
J 0
(-5730 3602);
DISPLAY 0.340426 (-5730 3602);
PAINT GREEN (-5730 3602);
DISPLAY INVISIBLE (-5730 3602);
FORCEPROP 2 LAST CDS_LIB mstr_symbols
J 0
(-5775 3600);
PAINT ORANGE (-5775 3600);
DISPLAY INVISIBLE (-5775 3600);
FORCEPROP 1 LAST BODY_TYPE PLUMBING
J 0
(-5820 3557);
DISPLAY 0.340426 (-5820 3557);
PAINT GREEN (-5820 3557);
DISPLAY INVISIBLE (-5820 3557);
FORCEPROP 1 LAST HDL_POWER P3V3_STBY
J 0
(-6075 3475);
DISPLAY 0.872340 (-6075 3475);
PAINT ORANGE (-6075 3475);
DISPLAY INVISIBLE (-6075 3475);
FORCEADD GND..1
(-6225 2025);
FORCEPROP 3 LASTPIN (-6225 2075) SIG_NAME GND\g
J 0
(-6215 2085);
DISPLAY 0.659574 (-6215 2085);
PAINT MONO (-6215 2085);
DISPLAY INVISIBLE (-6215 2085);
FORCEPROP 1 LAST SIZE 1B
J 0
(-6150 1975);
DISPLAY 0.872340 (-6150 1975);
PAINT AQUA (-6150 1975);
DISPLAY INVISIBLE (-6150 1975);
FORCEPROP 2 LAST CDS_LIB mstr_symbols
J 0
(-6225 2025);
PAINT ORANGE (-6225 2025);
DISPLAY INVISIBLE (-6225 2025);
FORCEPROP 1 LAST VOLTAGE 0.0V
J 0
(-6270 1982);
DISPLAY 0.340426 (-6270 1982);
PAINT GREEN (-6270 1982);
DISPLAY INVISIBLE (-6270 1982);
FORCEPROP 1 LAST PATH I7
J 0
(-6150 2025);
DISPLAY 0.872340 (-6150 2025);
PAINT AQUA (-6150 2025);
DISPLAY INVISIBLE (-6150 2025);
FORCEPROP 1 LAST BODY_TYPE PLUMBING
J 0
(-6270 1982);
DISPLAY 0.340426 (-6270 1982);
PAINT GREEN (-6270 1982);
DISPLAY INVISIBLE (-6270 1982);
FORCEPROP 1 LAST HDL_POWER GND
J 0
(-6225 2175);
DISPLAY 0.872340 (-6225 2175);
PAINT GREEN (-6225 2175);
DISPLAY INVISIBLE (-6225 2175);
FORCEADD RES..1
(-5725 2750);
FORCEPROP 1 LAST LOCATION RN8F5
J 0
(-6032 2757);
DISPLAY 0.617021 (-6032 2757);
PAINT AQUA (-6032 2757);
FORCEPROP 1 LAST VALUE 33.2
J 2
(-5500 2757);
DISPLAY 0.617021 (-5500 2757);
PAINT SKYBLUE (-5500 2757);
FORCEPROP 1 LASTPIN (-5625 2750) $PN 2
J 0
(-5663 2762);
DISPLAY 0.617021 (-5663 2762);
PAINT MONO (-5663 2762);
FORCEPROP 1 LASTPIN (-5825 2750) $PN 1
J 0
(-5813 2762);
DISPLAY 0.617021 (-5813 2762);
PAINT MONO (-5813 2762);
FORCEPROP 0 LAST CDS_LOCATION RN8F5
J 0
(-5500 2800);
PAINT MONO (-5500 2800);
DISPLAY INVISIBLE (-5500 2800);
FORCEPROP 2 LAST SEC 1
J 0
(-5775 2975);
DISPLAY 0.680851 (-5775 2975);
PAINT MONO (-5775 2975);
DISPLAY INVISIBLE (-5775 2975);
FORCEPROP 2 LAST SEC_TYPE 0402
J 0
(-5775 2975);
DISPLAY 1.021277 (-5775 2975);
PAINT ORANGE (-5775 2975);
DISPLAY INVISIBLE (-5775 2975);
FORCEPROP 1 LAST PART_NUMBER G21796-074
J 0
(-5775 2850);
PAINT BLUE (-5775 2850);
DISPLAY INVISIBLE (-5775 2850);
FORCEPROP 2 LAST BOM_COST SM_MEM
J 0
(-5500 2850);
DISPLAY 1.021277 (-5500 2850);
PAINT ORANGE (-5500 2850);
DISPLAY INVISIBLE (-5500 2850);
FORCEPROP 1 LAST PACK_TYPE 0402
J 0
(-5475 2600);
PAINT SKYBLUE (-5475 2600);
DISPLAY INVISIBLE (-5475 2600);
FORCEPROP 1 LAST MATERIAL CHIP
J 0
(-5525 2750);
PAINT SKYBLUE (-5525 2750);
DISPLAY INVISIBLE (-5525 2750);
FORCEPROP 2 LAST ROOM BMC_BOOT_SPI
J 0
(-5500 2800);
DISPLAY 1.021277 (-5500 2800);
PAINT ORANGE (-5500 2800);
DISPLAY INVISIBLE (-5500 2800);
FORCEPROP 2 LAST CDS_LIB mstr_discrete
J 1
(-5725 2750);
PAINT ORANGE (-5725 2750);
DISPLAY INVISIBLE (-5725 2750);
FORCEPROP 1 LAST TOLERANCE 1%
J 0
(-5650 2600);
PAINT SKYBLUE (-5650 2600);
DISPLAY INVISIBLE (-5650 2600);
FORCEPROP 1 LAST WATTAGE 1/16W
J 2
(-5750 2600);
PAINT SKYBLUE (-5750 2600);
DISPLAY INVISIBLE (-5750 2600);
FORCEPROP 0 LAST CDS_SEC 1
J 0
(-5500 2800);
PAINT MONO (-5500 2800);
DISPLAY INVISIBLE (-5500 2800);
FORCEPROP 1 LAST PATH I9
J 0
(-5775 2900);
DISPLAY 0.978723 (-5775 2900);
PAINT WHITE (-5775 2900);
DISPLAY INVISIBLE (-5775 2900);
FORCEADD DNS..2
(-5220 3220);
PAINT RED (-5220 3220);
FORCEPROP 2 LAST CDS_LIB mstr_misc
J 0
(-5220 3220);
PAINT ORANGE (-5220 3220);
DISPLAY INVISIBLE (-5220 3220);
FORCEPROP 1 LAST COMMENT_BODY TRUE
R 1
J 0
(-5145 2995);
DISPLAY 0.872340 (-5145 2995);
PAINT GREEN (-5145 2995);
DISPLAY INVISIBLE (-5145 2995);
FORCEADD CAD_NOTE..1
(-3925 2025);
FORCEPROP 0 LAST L2 USE ALT SYMBOL ASSOCIATED WITH PART FOOTPRINT
J 0
(-4075 1875);
DISPLAY 0.617021 (-4075 1875);
PAINT WHITE (-4075 1875);
FORCEPROP 0 LAST L1 THIS PART WILL BE IN SOCKET, PLEASE
J 0
(-4075 1925);
DISPLAY 0.617021 (-4075 1925);
PAINT WHITE (-4075 1925);
FORCEPROP 2 LAST CDS_LIB mstr_symbols
J 0
(-3925 2025);
PAINT WHITE (-3925 2025);
DISPLAY INVISIBLE (-3925 2025);
FORCEPROP 1 LAST COMMENT_BODY TRUE
J 0
(-3900 2125);
DISPLAY 1.319149 (-3900 2125);
PAINT WHITE (-3900 2125);
DISPLAY INVISIBLE (-3900 2125);
FORCEADD BOM_NOTE..1
(-3925 1725);
FORCEPROP 0 LAST L1 SOCKET IS D91187-001
J 0
(-4075 1625);
DISPLAY 0.617021 (-4075 1625);
PAINT WHITE (-4075 1625);
FORCEPROP 2 LAST CDS_LIB mstr_symbols
J 0
(-3925 1725);
PAINT WHITE (-3925 1725);
DISPLAY INVISIBLE (-3925 1725);
FORCEPROP 1 LAST COMMENT_BODY TRUE
J 0
(-3900 1825);
DISPLAY 1.319149 (-3900 1825);
PAINT WHITE (-3900 1825);
DISPLAY INVISIBLE (-3900 1825);
FORCEADD CAD_NOTE..1
(-2275 3300);
FORCEPROP 0 LAST L1 PLACE CAPS NEAR VCC PIN ON W25Q256 COMPONENT
J 0
(-2425 3175);
DISPLAY 1.021277 (-2425 3175);
PAINT ORANGE (-2425 3175);
FORCEPROP 2 LAST CDS_LIB mstr_symbols
J 0
(-2275 3300);
PAINT ORANGE (-2275 3300);
DISPLAY INVISIBLE (-2275 3300);
FORCEPROP 1 LAST COMMENT_BODY TRUE
J 0
(-2250 3400);
DISPLAY 0.978723 (-2250 3400);
PAINT ORANGE (-2250 3400);
DISPLAY INVISIBLE (-2250 3400);
FORCEADD DNS..2
(-6220 3220);
PAINT RED (-6220 3220);
FORCEPROP 2 LAST CDS_LIB mstr_misc
J 0
(-6220 3220);
PAINT MONO (-6220 3220);
DISPLAY INVISIBLE (-6220 3220);
FORCEPROP 1 LAST COMMENT_BODY TRUE
R 1
J 0
(-6145 2995);
DISPLAY 0.872340 (-6145 2995);
PAINT GREEN (-6145 2995);
DISPLAY INVISIBLE (-6145 2995);
FORCEADD INTEL_CORP_BPAGE..1
(0 0);
FORCEPROP 1 LAST CDS_CON_LAST_MODIFIED Fri Jun 16 17:49:29 2017
J 0
(-1425 325);
PAINT ORANGE (-1425 325);
DISPLAY INVISIBLE (-1425 325);
FORCEPROP 1 LAST CUSTOM_TXT_CDS <CURRENT_DESIGN_SHEET> OF <TOTAL_DESIGN_SHEETS>
J 0
(-500 25);
PAINT ORANGE (-500 25);
FORCEPROP 1 LAST CUSTOM_TXT_CDS <CON_LAST_MODIFIED>
J 0
(-4000 100);
PAINT ORANGE (-4000 100);
FORCEPROP 2 LAST CUSTOM_TXT_CDS <XR_PAGE_TITLE>
J 0
(-7890 5250);
DISPLAY 0.638298 (-7890 5250);
PAINT PINK (-7890 5250);
DISPLAY INVISIBLE (-7890 5250);
FORCEPROP 1 LAST SCH_TITLE BMC SECURE FLASH
J 0
(-7950 50);
DISPLAY 2.468085 (-7950 50);
PAINT ORANGE (-7950 50);
FORCEPROP 2 LAST CDS_LIB mstr_symbols
J 0
(0 0);
PAINT MONO (0 0);
DISPLAY INVISIBLE (0 0);
FORCEPROP 2 LAST PAGE_BORDER TRUE
J 0
(-7890 5250);
DISPLAY 0.638298 (-7890 5250);
PAINT PINK (-7890 5250);
DISPLAY INVISIBLE (-7890 5250);
FORCEPROP 1 LAST COMMENT_BODY TRUE
J 0
(12 12);
DISPLAY 0.468085 (12 12);
PAINT GREEN (12 12);
DISPLAY INVISIBLE (12 12);
FORCEPROP 2 LAST CDS_XR_PAGE_TITLE CR-246 : @BASEBOARD_FAB2_LIB.BASEBOARD_FAB2(SCH_1):PAGE246
J 0
(-7890 5250);
DISPLAY 0.638298 (-7890 5250);
PAINT PINK (-7890 5250);
DISPLAY INVISIBLE (-7890 5250);
WIRE 16 -1 (-3025 2350)(-3025 2500);
WIRE 16 -1 (-3025 2500)(-3125 2500);
WIRE 16 -1 (-2700 3000)(-2700 3050);
WIRE 16 -1 (-2700 3050)(-3000 3050);
WIRE 16 -1 (-2700 3175)(-2700 3050);
WIRE 16 -1 (-3000 3050)(-3000 3175);
WIRE 16 -1 (-5775 3550)(-5775 3425);
WIRE 16 -1 (-5225 3425)(-5775 3425);
WIRE 16 -1 (-5775 3425)(-6225 3425);
WIRE 16 -1 (-5775 3300)(-5775 3425);
WIRE 16 -1 (-6225 3325)(-6225 3425);
WIRE 16 -1 (-5225 3425)(-4925 3425);
WIRE 16 -1 (-5225 3325)(-5225 3425);
WIRE 16 -1 (-4925 3425)(-4925 2950);
WIRE 16 -1 (-3000 3425)(-4925 3425);
WIRE 16 -1 (-2700 3425)(-3000 3425);
WIRE 16 -1 (-3000 3425)(-3000 3375);
WIRE 16 -1 (-4925 2950)(-4225 2950);
WIRE 16 -1 (-2700 3375)(-2700 3425);
WIRE 16 -1 (-6225 2075)(-6225 2175);
WIRE 16 -1 (-2750 2800)(-3125 2800);
FORCEPROP 2 LAST SIG_NAME TP_TPM_SPI_3
J 0
(-3060 2810);
DISPLAY 0.617021 (-3060 2810);
PAINT ORANGE (-3060 2810);
FORCEPROP 2 LASTPROP $XRERR UNIQUE?
J 0
(-2720 2800);
DISPLAY 0.638298 (-2720 2800);
PAINT MONO (-2720 2800);
DISPLAY INVISIBLE (-2720 2800);
WIRE 3 2175 (-7775 800)(-550 800);
WIRE 3 2175 (-550 4550)(-550 800);
WIRE 3 2175 (-7775 4550)(-7775 800);
WIRE 3 2175 (-7775 4550)(-550 4550);
WIRE 16 -1 (-4225 2700)(-7075 2700);
FORCEPROP 2 LAST SIG_NAME SPI_BMC_BT_DO
J 0
(-7025 2710);
DISPLAY 0.617021 (-7025 2710);
PAINT ORANGE (-7025 2710);
WIRE 16 -1 (-7075 2600)(-4225 2600);
FORCEPROP 2 LAST SIG_NAME SPI_BMC_BT_CLK
J 0
(-7025 2610);
DISPLAY 0.617021 (-7025 2610);
PAINT ORANGE (-7025 2610);
WIRE 16 -1 (-7075 2500)(-4225 2500);
FORCEPROP 2 LAST SIG_NAME SPI_BMC_BT_CS0_N
J 2
(-6675 2510);
DISPLAY 0.680851 (-6675 2510);
PAINT ORANGE (-6675 2510);
WIRE 16 -1 (-5225 3125)(-5225 2450);
FORCEPROP 2 LAST SIG_NAME PU_TPM_SPI_FLASH_RESET_2_N
J 0
(-5160 2460);
DISPLAY 0.617021 (-5160 2460);
PAINT ORANGE (-5160 2460);
FORCEPROP 2 LASTPROP $XRERR UNIQUE?
J 0
(-5400 2460);
DISPLAY 0.638298 (-5400 2460);
PAINT MONO (-5400 2460);
DISPLAY INVISIBLE (-5400 2460);
WIRE 16 -1 (-5225 2450)(-4225 2450);
WIRE 16 -1 (-2750 2950)(-3125 2950);
FORCEPROP 2 LAST SIG_NAME TP_TPM_SPI_6
J 0
(-3060 2960);
DISPLAY 0.617021 (-3060 2960);
PAINT ORANGE (-3060 2960);
FORCEPROP 2 LASTPROP $XRERR UNIQUE?
J 0
(-2720 2950);
DISPLAY 0.638298 (-2720 2950);
PAINT MONO (-2720 2950);
DISPLAY INVISIBLE (-2720 2950);
WIRE 16 -1 (-2750 2850)(-3125 2850);
FORCEPROP 2 LAST SIG_NAME TP_TPM_SPI_4
J 0
(-3060 2860);
DISPLAY 0.617021 (-3060 2860);
PAINT ORANGE (-3060 2860);
FORCEPROP 2 LASTPROP $XRERR UNIQUE?
J 0
(-2720 2850);
DISPLAY 0.638298 (-2720 2850);
PAINT MONO (-2720 2850);
DISPLAY INVISIBLE (-2720 2850);
WIRE 16 -1 (-2750 2900)(-3125 2900);
FORCEPROP 2 LAST SIG_NAME TP_TPM_SPI_5
J 0
(-3060 2910);
DISPLAY 0.617021 (-3060 2910);
PAINT ORANGE (-3060 2910);
FORCEPROP 2 LASTPROP $XRERR UNIQUE?
J 0
(-2720 2900);
DISPLAY 0.638298 (-2720 2900);
PAINT MONO (-2720 2900);
DISPLAY INVISIBLE (-2720 2900);
WIRE 3 682 (-6650 2450)(-6350 2450);
WIRE 3 682 (-6650 2575)(-6650 2450);
WIRE 3 682 (-6350 2450)(-6350 2575);
WIRE 3 682 (-6350 2575)(-6650 2575);
WIRE 16 -1 (-5775 2850)(-4225 2850);
FORCEPROP 2 LAST SIG_NAME PU_TPM_SPI_BMC_HOLD_N
J 0
(-5710 2860);
DISPLAY 0.617021 (-5710 2860);
PAINT ORANGE (-5710 2860);
FORCEPROP 2 LASTPROP $XRERR UNIQUE?
J 0
(-5950 2860);
DISPLAY 0.638298 (-5950 2860);
PAINT MONO (-5950 2860);
DISPLAY INVISIBLE (-5950 2860);
WIRE 16 -1 (-5775 3100)(-5775 2850);
WIRE 16 -1 (-7075 2750)(-5825 2750);
FORCEPROP 2 LAST SIG_NAME SPI_BMC_BT_DI
J 0
(-7025 2760);
DISPLAY 0.617021 (-7025 2760);
PAINT ORANGE (-7025 2760);
WIRE 16 -1 (-2750 2750)(-3125 2750);
FORCEPROP 2 LAST SIG_NAME TP_TPM_SPI_2
J 0
(-3060 2760);
DISPLAY 0.617021 (-3060 2760);
PAINT ORANGE (-3060 2760);
FORCEPROP 2 LASTPROP $XRERR UNIQUE?
J 0
(-2720 2750);
DISPLAY 0.638298 (-2720 2750);
PAINT MONO (-2720 2750);
DISPLAY INVISIBLE (-2720 2750);
WIRE 16 -1 (-2750 2700)(-3125 2700);
FORCEPROP 2 LAST SIG_NAME TP_TPM_SPI_1
J 0
(-3060 2710);
DISPLAY 0.617021 (-3060 2710);
PAINT ORANGE (-3060 2710);
FORCEPROP 2 LASTPROP $XRERR UNIQUE?
J 0
(-2720 2700);
DISPLAY 0.638298 (-2720 2700);
PAINT MONO (-2720 2700);
DISPLAY INVISIBLE (-2720 2700);
WIRE 16 -1 (-2750 2650)(-3125 2650);
FORCEPROP 2 LAST SIG_NAME TP_TPM_SPI_0
J 0
(-3060 2660);
DISPLAY 0.617021 (-3060 2660);
PAINT ORANGE (-3060 2660);
FORCEPROP 2 LASTPROP $XRERR UNIQUE?
J 0
(-2720 2650);
DISPLAY 0.638298 (-2720 2650);
PAINT MONO (-2720 2650);
DISPLAY INVISIBLE (-2720 2650);
WIRE 16 -1 (-4225 2750)(-5625 2750);
FORCEPROP 2 LAST SIG_NAME SPI_TPM_BMC_DI_R
J 2
(-4575 2760);
DISPLAY 0.617021 (-4575 2760);
PAINT ORANGE (-4575 2760);
FORCEPROP 2 LASTPROP $XRERR UNIQUE?
J 0
(-4815 2760);
DISPLAY 0.638298 (-4815 2760);
PAINT MONO (-4815 2760);
DISPLAY INVISIBLE (-4815 2760);
WIRE 16 -1 (-6225 2800)(-7075 2800);
WIRE 16 -1 (-6225 2425)(-6225 2800);
WIRE 16 -1 (-6225 3125)(-6225 2800);
WIRE 16 -1 (-4225 2800)(-6225 2800);
FORCEPROP 2 LAST SIG_NAME TPM_SPI_BMC_WP_N
J 0
(-7010 2810);
DISPLAY 0.617021 (-7010 2810);
PAINT ORANGE (-7010 2810);
DOT 1 (-4925 3425);
DOT 1 (-5225 3425);
DOT 1 (-5775 3425);
DOT 1 (-6225 2800);
DOT 1 (-3000 3425);
DOT 1 (-2700 3050);
FORCENOTE
TP FAB1 CONNECT WP_N TO BMC GPIO  BY A JUMPER
(-4950 1000) 0;
DISPLAY LEFT (-4950 1000);
DISPLAY 1.702128 (-4950 1000);
PAINT RED (-4950 1000);
FORCENOTE
UN8F2 IS SOCKET.
(-4175 2150) 0;
DISPLAY LEFT (-4175 2150);
DISPLAY 1.021277 (-4175 2150);
PAINT PURPLE (-4175 2150);
FORCENOTE
TP FAB1 MOVE PU RN8F1 TO PAGE 137 0308
(-7725 2300) 0;
DISPLAY LEFT (-7725 2300);
DISPLAY 1.021277 (-7725 2300);
PAINT RED (-7725 2300);
FORCENOTE
TP FAB1 ADD TPM FLASH
(-4950 1100) 0;
DISPLAY LEFT (-4950 1100);
DISPLAY 1.702128 (-4950 1100);
PAINT RED (-4950 1100);
QUIT
